(kicad_pcb
	(version 20260206)
	(generator "pcbnew")
	(generator_version "10.0")
	(general
		(thickness 1.6)
		(legacy_teardrops no)
	)
	(paper "A4")
	(title_block
		(title "04192023_DAF0TMB3IC0_F0TG_MB_C_brd_V02_OCP.brd")
		(comment 1 "Grand Teton / footprints 3905-3911 of 8354")
	)
	(layers
		(0 "F.Cu" signal "TOP")
		(4 "In1.Cu" signal "GND")
		(6 "In2.Cu" signal "IN1")
		(8 "In3.Cu" signal "GND1")
		(10 "In4.Cu" signal "IN2")
		(12 "In5.Cu" signal "GND2")
		(14 "In6.Cu" signal "IN3")
		(16 "In7.Cu" signal "GND3")
		(18 "In8.Cu" signal "VCC")
		(20 "In9.Cu" signal "VCC1")
		(22 "In10.Cu" signal "GND4")
		(24 "In11.Cu" signal "IN4")
		(26 "In12.Cu" signal "GND5")
		(28 "In13.Cu" signal "IN5")
		(30 "In14.Cu" signal "GND6")
		(32 "In15.Cu" signal "IN6")
		(34 "In16.Cu" signal "GND7")
		(2 "B.Cu" signal "BOTTOM")
		(9 "F.Adhes" user "F.Adhesive")
		(11 "B.Adhes" user "B.Adhesive")
		(13 "F.Paste" user "Package Geometry/Pastemask Top")
		(15 "B.Paste" user "Package Geometry/Pastemask Bottom")
		(5 "F.SilkS" user "Ref Des/Silkscreen Top")
		(7 "B.SilkS" user "Ref Des/Silkscreen Bottom")
		(1 "F.Mask" user "Board Geometry/Soldermask Top")
		(3 "B.Mask" user "Board Geometry/Soldermask Bottom")
		(17 "Dwgs.User" user "User.Drawings")
		(19 "Cmts.User" user "User.Comments")
		(21 "Eco1.User" user "User.Eco1")
		(23 "Eco2.User" user "User.Eco2")
		(25 "Edge.Cuts" user "Board Geometry/Outline")
		(27 "Margin" user)
		(31 "F.CrtYd" user "Package Geometry/Place Bound Top")
		(29 "B.CrtYd" user "Package Geometry/Place Bound Bottom")
		(35 "F.Fab" user "Ref Des/Assembly Top")
		(33 "B.Fab" user "Ref Des/Assembly Bottom")
	)
	(footprint ""
		(layer "F.Cu")
		(at 180.528468 -50.974498)
		(property "Reference" "C1101"
			(at 0 0 0)
			(layer "F.SilkS")
			(hide yes)
			(effects
				(font
					(size 1.27 1.27)
				)
			)
		)
		(property "Value" ""
			(at 0 0 0)
			(layer "F.Fab")
			(effects
				(font
					(size 1.27 1.27)
				)
			)
		)
		(duplicate_pad_numbers_are_jumpers no)
		(fp_line
			(start -0.299974 -0.150114)
			(end 0.299974 -0.150114)
			(stroke
				(width 0.1)
				(type default)
			)
			(layer "F.Fab")
		)
		(fp_line
			(start -0.299974 0.150114)
			(end -0.299974 -0.150114)
			(stroke
				(width 0.1)
				(type default)
			)
			(layer "F.Fab")
		)
		(fp_line
			(start 0.299974 -0.150114)
			(end 0.299974 0.150114)
			(stroke
				(width 0.1)
				(type default)
			)
			(layer "F.Fab")
		)
		(fp_line
			(start 0.299974 0.150114)
			(end -0.299974 0.150114)
			(stroke
				(width 0.1)
				(type default)
			)
			(layer "F.Fab")
		)
		(pad "1" smd rect
			(at -0.2667 0)
			(size 0.3048 0.381)
			(layers "F.Cu" "F.Mask" "F.Paste")
			(net "P3E_CPU1_P4_TX_C_DN<2>")
		)
		(pad "2" smd rect
			(at 0.2667 0)
			(size 0.3048 0.381)
			(layers "F.Cu" "F.Mask" "F.Paste")
			(net "P3E_CPU1_P4_TX_DN<2>")
		)
	)
	(footprint ""
		(layer "F.Cu")
		(at 314.668662 -333.260954 90)
		(property "Reference" "PR510"
			(at 0 0 90)
			(layer "F.SilkS")
			(hide yes)
			(effects
				(font
					(size 1.27 1.27)
				)
			)
		)
		(property "Value" ""
			(at 0 0 90)
			(layer "F.Fab")
			(effects
				(font
					(size 1.27 1.27)
				)
			)
		)
		(duplicate_pad_numbers_are_jumpers no)
		(fp_line
			(start 0.7874 -0.4064)
			(end 0.7874 0.4064)
			(stroke
				(width 0.1524)
				(type default)
			)
			(layer "F.SilkS")
		)
		(fp_line
			(start -0.7874 -0.4064)
			(end 0.7874 -0.4064)
			(stroke
				(width 0.1524)
				(type default)
			)
			(layer "F.SilkS")
		)
		(fp_line
			(start 0.7874 0.4064)
			(end -0.7874 0.4064)
			(stroke
				(width 0.1524)
				(type default)
			)
			(layer "F.SilkS")
		)
		(fp_line
			(start -0.7874 0.4064)
			(end -0.7874 -0.4064)
			(stroke
				(width 0.1524)
				(type default)
			)
			(layer "F.SilkS")
		)
		(fp_line
			(start -0.12065 -0.305054)
			(end -0.12065 -0.2794)
			(stroke
				(width 0.1)
				(type default)
			)
			(layer "F.Fab")
		)
		(fp_line
			(start -0.67945 -0.305054)
			(end -0.12065 -0.305054)
			(stroke
				(width 0.1)
				(type default)
			)
			(layer "F.Fab")
		)
		(fp_line
			(start 0.67945 -0.3048)
			(end 0.67945 0.3048)
			(stroke
				(width 0.1)
				(type default)
			)
			(layer "F.Fab")
		)
		(fp_line
			(start 0.12065 -0.3048)
			(end 0.67945 -0.3048)
			(stroke
				(width 0.1)
				(type default)
			)
			(layer "F.Fab")
		)
		(fp_line
			(start 0.12065 -0.2794)
			(end 0.12065 -0.3048)
			(stroke
				(width 0.1)
				(type default)
			)
			(layer "F.Fab")
		)
		(fp_line
			(start -0.12065 -0.2794)
			(end 0.12065 -0.2794)
			(stroke
				(width 0.1)
				(type default)
			)
			(layer "F.Fab")
		)
		(fp_line
			(start 0.120396 0.2794)
			(end -0.12065 0.2794)
			(stroke
				(width 0.1)
				(type default)
			)
			(layer "F.Fab")
		)
		(fp_line
			(start -0.12065 0.2794)
			(end -0.12065 0.3048)
			(stroke
				(width 0.1)
				(type default)
			)
			(layer "F.Fab")
		)
		(fp_line
			(start 0.67945 0.3048)
			(end 0.120396 0.3048)
			(stroke
				(width 0.1)
				(type default)
			)
			(layer "F.Fab")
		)
		(fp_line
			(start 0.120396 0.3048)
			(end 0.120396 0.2794)
			(stroke
				(width 0.1)
				(type default)
			)
			(layer "F.Fab")
		)
		(fp_line
			(start -0.12065 0.3048)
			(end -0.67945 0.3048)
			(stroke
				(width 0.1)
				(type default)
			)
			(layer "F.Fab")
		)
		(fp_line
			(start -0.67945 0.3048)
			(end -0.67945 -0.305054)
			(stroke
				(width 0.1)
				(type default)
			)
			(layer "F.Fab")
		)
		(pad "1" smd circle
			(at -0.40005 0 90)
			(size 0 0)
			(layers "F.Cu" "F.Mask" "F.Paste")
			(net "SW_PVDDCR_CPU1_P0_SW3_RC")
		)
		(pad "2" smd circle
			(at 0.40005 0 90)
			(size 0 0)
			(layers "F.Cu" "F.Mask" "F.Paste")
			(net "GND")
		)
	)
	(footprint ""
		(layer "F.Cu")
		(at 292.767512 -351.368106 90)
		(property "Reference" "PR102"
			(at 0 0 90)
			(layer "F.SilkS")
			(hide yes)
			(effects
				(font
					(size 1.27 1.27)
				)
			)
		)
		(property "Value" ""
			(at 0 0 90)
			(layer "F.Fab")
			(effects
				(font
					(size 1.27 1.27)
				)
			)
		)
		(duplicate_pad_numbers_are_jumpers no)
		(fp_line
			(start 0.7874 -0.4064)
			(end 0.7874 0.4064)
			(stroke
				(width 0.1524)
				(type default)
			)
			(layer "F.SilkS")
		)
		(fp_line
			(start -0.7874 -0.4064)
			(end 0.7874 -0.4064)
			(stroke
				(width 0.1524)
				(type default)
			)
			(layer "F.SilkS")
		)
		(fp_line
			(start 0.7874 0.4064)
			(end -0.7874 0.4064)
			(stroke
				(width 0.1524)
				(type default)
			)
			(layer "F.SilkS")
		)
		(fp_line
			(start -0.7874 0.4064)
			(end -0.7874 -0.4064)
			(stroke
				(width 0.1524)
				(type default)
			)
			(layer "F.SilkS")
		)
		(fp_line
			(start -0.12065 -0.305054)
			(end -0.12065 -0.2794)
			(stroke
				(width 0.1)
				(type default)
			)
			(layer "F.Fab")
		)
		(fp_line
			(start -0.67945 -0.305054)
			(end -0.12065 -0.305054)
			(stroke
				(width 0.1)
				(type default)
			)
			(layer "F.Fab")
		)
		(fp_line
			(start 0.67945 -0.3048)
			(end 0.67945 0.3048)
			(stroke
				(width 0.1)
				(type default)
			)
			(layer "F.Fab")
		)
		(fp_line
			(start 0.12065 -0.3048)
			(end 0.67945 -0.3048)
			(stroke
				(width 0.1)
				(type default)
			)
			(layer "F.Fab")
		)
		(fp_line
			(start 0.12065 -0.2794)
			(end 0.12065 -0.3048)
			(stroke
				(width 0.1)
				(type default)
			)
			(layer "F.Fab")
		)
		(fp_line
			(start -0.12065 -0.2794)
			(end 0.12065 -0.2794)
			(stroke
				(width 0.1)
				(type default)
			)
			(layer "F.Fab")
		)
		(fp_line
			(start 0.120396 0.2794)
			(end -0.12065 0.2794)
			(stroke
				(width 0.1)
				(type default)
			)
			(layer "F.Fab")
		)
		(fp_line
			(start -0.12065 0.2794)
			(end -0.12065 0.3048)
			(stroke
				(width 0.1)
				(type default)
			)
			(layer "F.Fab")
		)
		(fp_line
			(start 0.67945 0.3048)
			(end 0.120396 0.3048)
			(stroke
				(width 0.1)
				(type default)
			)
			(layer "F.Fab")
		)
		(fp_line
			(start 0.120396 0.3048)
			(end 0.120396 0.2794)
			(stroke
				(width 0.1)
				(type default)
			)
			(layer "F.Fab")
		)
		(fp_line
			(start -0.12065 0.3048)
			(end -0.67945 0.3048)
			(stroke
				(width 0.1)
				(type default)
			)
			(layer "F.Fab")
		)
		(fp_line
			(start -0.67945 0.3048)
			(end -0.67945 -0.305054)
			(stroke
				(width 0.1)
				(type default)
			)
			(layer "F.Fab")
		)
		(pad "1" smd circle
			(at -0.40005 0 90)
			(size 0 0)
			(layers "F.Cu" "F.Mask" "F.Paste")
			(net "SW_PVDDIO_P0_BOOT2")
		)
		(pad "2" smd circle
			(at 0.40005 0 90)
			(size 0 0)
			(layers "F.Cu" "F.Mask" "F.Paste")
			(net "SW_PVDDIO_P0_BOOT2_R")
		)
	)
	(footprint ""
		(layer "F.Cu")
		(at 424.14444 -378.95403 -90)
		(property "Reference" "C843"
			(at 0 0 270)
			(layer "F.SilkS")
			(hide yes)
			(effects
				(font
					(size 1.27 1.27)
				)
			)
		)
		(property "Value" ""
			(at 0 0 270)
			(layer "F.Fab")
			(effects
				(font
					(size 1.27 1.27)
				)
			)
		)
		(duplicate_pad_numbers_are_jumpers no)
		(fp_line
			(start -0.299974 0.150114)
			(end -0.299974 -0.150114)
			(stroke
				(width 0.1)
				(type default)
			)
			(layer "F.Fab")
		)
		(fp_line
			(start 0.299974 0.150114)
			(end -0.299974 0.150114)
			(stroke
				(width 0.1)
				(type default)
			)
			(layer "F.Fab")
		)
		(fp_line
			(start -0.299974 -0.150114)
			(end 0.299974 -0.150114)
			(stroke
				(width 0.1)
				(type default)
			)
			(layer "F.Fab")
		)
		(fp_line
			(start 0.299974 -0.150114)
			(end 0.299974 0.150114)
			(stroke
				(width 0.1)
				(type default)
			)
			(layer "F.Fab")
		)
		(pad "1" smd rect
			(at -0.2667 0 270)
			(size 0.3048 0.381)
			(layers "F.Cu" "F.Mask" "F.Paste")
			(net "P5E_CPU0_P2_TX_C_DP<13>")
		)
		(pad "2" smd rect
			(at 0.2667 0 270)
			(size 0.3048 0.381)
			(layers "F.Cu" "F.Mask" "F.Paste")
			(net "P5E_CPU0_P2_TX_DP<13>")
		)
	)
	(footprint ""
		(layer "F.Cu")
		(at 68.516754 -370.57203 -90)
		(property "Reference" "C810"
			(at 0 0 270)
			(layer "F.SilkS")
			(hide yes)
			(effects
				(font
					(size 1.27 1.27)
				)
			)
		)
		(property "Value" ""
			(at 0 0 270)
			(layer "F.Fab")
			(effects
				(font
					(size 1.27 1.27)
				)
			)
		)
		(duplicate_pad_numbers_are_jumpers no)
		(fp_line
			(start -0.299974 0.150114)
			(end -0.299974 -0.150114)
			(stroke
				(width 0.1)
				(type default)
			)
			(layer "F.Fab")
		)
		(fp_line
			(start 0.299974 0.150114)
			(end -0.299974 0.150114)
			(stroke
				(width 0.1)
				(type default)
			)
			(layer "F.Fab")
		)
		(fp_line
			(start -0.299974 -0.150114)
			(end 0.299974 -0.150114)
			(stroke
				(width 0.1)
				(type default)
			)
			(layer "F.Fab")
		)
		(fp_line
			(start 0.299974 -0.150114)
			(end 0.299974 0.150114)
			(stroke
				(width 0.1)
				(type default)
			)
			(layer "F.Fab")
		)
		(pad "1" smd rect
			(at -0.2667 0 270)
			(size 0.3048 0.381)
			(layers "F.Cu" "F.Mask" "F.Paste")
			(net "P5E_CPU1_P0_TX_C_DN<13>")
		)
		(pad "2" smd rect
			(at 0.2667 0 270)
			(size 0.3048 0.381)
			(layers "F.Cu" "F.Mask" "F.Paste")
			(net "P5E_CPU1_P0_TX_DN<13>")
		)
	)
	(footprint ""
		(layer "F.Cu")
		(at 75.64501 -148.451316 90)
		(property "Reference" "R8009"
			(at 0 0 90)
			(layer "F.SilkS")
			(hide yes)
			(effects
				(font
					(size 1.27 1.27)
				)
			)
		)
		(property "Value" ""
			(at 0 0 90)
			(layer "F.Fab")
			(effects
				(font
					(size 1.27 1.27)
				)
			)
		)
		(duplicate_pad_numbers_are_jumpers no)
		(fp_line
			(start 0.7874 -0.4064)
			(end 0.7874 0.4064)
			(stroke
				(width 0.1524)
				(type default)
			)
			(layer "F.SilkS")
		)
		(fp_line
			(start -0.7874 -0.4064)
			(end 0.7874 -0.4064)
			(stroke
				(width 0.1524)
				(type default)
			)
			(layer "F.SilkS")
		)
		(fp_line
			(start 0.7874 0.4064)
			(end -0.7874 0.4064)
			(stroke
				(width 0.1524)
				(type default)
			)
			(layer "F.SilkS")
		)
		(fp_line
			(start -0.7874 0.4064)
			(end -0.7874 -0.4064)
			(stroke
				(width 0.1524)
				(type default)
			)
			(layer "F.SilkS")
		)
		(fp_line
			(start -0.12065 -0.305054)
			(end -0.12065 -0.2794)
			(stroke
				(width 0.1)
				(type default)
			)
			(layer "F.Fab")
		)
		(fp_line
			(start -0.67945 -0.305054)
			(end -0.12065 -0.305054)
			(stroke
				(width 0.1)
				(type default)
			)
			(layer "F.Fab")
		)
		(fp_line
			(start 0.67945 -0.3048)
			(end 0.67945 0.3048)
			(stroke
				(width 0.1)
				(type default)
			)
			(layer "F.Fab")
		)
		(fp_line
			(start 0.12065 -0.3048)
			(end 0.67945 -0.3048)
			(stroke
				(width 0.1)
				(type default)
			)
			(layer "F.Fab")
		)
		(fp_line
			(start 0.12065 -0.2794)
			(end 0.12065 -0.3048)
			(stroke
				(width 0.1)
				(type default)
			)
			(layer "F.Fab")
		)
		(fp_line
			(start -0.12065 -0.2794)
			(end 0.12065 -0.2794)
			(stroke
				(width 0.1)
				(type default)
			)
			(layer "F.Fab")
		)
		(fp_line
			(start 0.120396 0.2794)
			(end -0.12065 0.2794)
			(stroke
				(width 0.1)
				(type default)
			)
			(layer "F.Fab")
		)
		(fp_line
			(start -0.12065 0.2794)
			(end -0.12065 0.3048)
			(stroke
				(width 0.1)
				(type default)
			)
			(layer "F.Fab")
		)
		(fp_line
			(start 0.67945 0.3048)
			(end 0.120396 0.3048)
			(stroke
				(width 0.1)
				(type default)
			)
			(layer "F.Fab")
		)
		(fp_line
			(start 0.120396 0.3048)
			(end 0.120396 0.2794)
			(stroke
				(width 0.1)
				(type default)
			)
			(layer "F.Fab")
		)
		(fp_line
			(start -0.12065 0.3048)
			(end -0.67945 0.3048)
			(stroke
				(width 0.1)
				(type default)
			)
			(layer "F.Fab")
		)
		(fp_line
			(start -0.67945 0.3048)
			(end -0.67945 -0.305054)
			(stroke
				(width 0.1)
				(type default)
			)
			(layer "F.Fab")
		)
		(pad "1" smd circle
			(at -0.40005 0 90)
			(size 0 0)
			(layers "F.Cu" "F.Mask" "F.Paste")
			(net "P3V3_AUX")
		)
		(pad "2" smd circle
			(at 0.40005 0 90)
			(size 0 0)
			(layers "F.Cu" "F.Mask" "F.Paste")
			(net "PWRGD_PVDD18_S5_P1")
		)
	)
	(footprint ""
		(layer "F.Cu")
		(at 179.9082 -96.103948 90)
		(property "Reference" "R187"
			(at 0 0 90)
			(layer "F.SilkS")
			(hide yes)
			(effects
				(font
					(size 1.27 1.27)
				)
			)
		)
		(property "Value" ""
			(at 0 0 90)
			(layer "F.Fab")
			(effects
				(font
					(size 1.27 1.27)
				)
			)
		)
		(duplicate_pad_numbers_are_jumpers no)
		(fp_line
			(start 0.7874 -0.4064)
			(end 0.7874 0.4064)
			(stroke
				(width 0.1524)
				(type default)
			)
			(layer "F.SilkS")
		)
		(fp_line
			(start -0.7874 -0.4064)
			(end 0.7874 -0.4064)
			(stroke
				(width 0.1524)
				(type default)
			)
			(layer "F.SilkS")
		)
		(fp_line
			(start 0.7874 0.4064)
			(end -0.7874 0.4064)
			(stroke
				(width 0.1524)
				(type default)
			)
			(layer "F.SilkS")
		)
		(fp_line
			(start -0.7874 0.4064)
			(end -0.7874 -0.4064)
			(stroke
				(width 0.1524)
				(type default)
			)
			(layer "F.SilkS")
		)
		(fp_line
			(start -0.12065 -0.305054)
			(end -0.12065 -0.2794)
			(stroke
				(width 0.1)
				(type default)
			)
			(layer "F.Fab")
		)
		(fp_line
			(start -0.67945 -0.305054)
			(end -0.12065 -0.305054)
			(stroke
				(width 0.1)
				(type default)
			)
			(layer "F.Fab")
		)
		(fp_line
			(start 0.67945 -0.3048)
			(end 0.67945 0.3048)
			(stroke
				(width 0.1)
				(type default)
			)
			(layer "F.Fab")
		)
		(fp_line
			(start 0.12065 -0.3048)
			(end 0.67945 -0.3048)
			(stroke
				(width 0.1)
				(type default)
			)
			(layer "F.Fab")
		)
		(fp_line
			(start 0.12065 -0.2794)
			(end 0.12065 -0.3048)
			(stroke
				(width 0.1)
				(type default)
			)
			(layer "F.Fab")
		)
		(fp_line
			(start -0.12065 -0.2794)
			(end 0.12065 -0.2794)
			(stroke
				(width 0.1)
				(type default)
			)
			(layer "F.Fab")
		)
		(fp_line
			(start 0.120396 0.2794)
			(end -0.12065 0.2794)
			(stroke
				(width 0.1)
				(type default)
			)
			(layer "F.Fab")
		)
		(fp_line
			(start -0.12065 0.2794)
			(end -0.12065 0.3048)
			(stroke
				(width 0.1)
				(type default)
			)
			(layer "F.Fab")
		)
		(fp_line
			(start 0.67945 0.3048)
			(end 0.120396 0.3048)
			(stroke
				(width 0.1)
				(type default)
			)
			(layer "F.Fab")
		)
		(fp_line
			(start 0.120396 0.3048)
			(end 0.120396 0.2794)
			(stroke
				(width 0.1)
				(type default)
			)
			(layer "F.Fab")
		)
		(fp_line
			(start -0.12065 0.3048)
			(end -0.67945 0.3048)
			(stroke
				(width 0.1)
				(type default)
			)
			(layer "F.Fab")
		)
		(fp_line
			(start -0.67945 0.3048)
			(end -0.67945 -0.305054)
			(stroke
				(width 0.1)
				(type default)
			)
			(layer "F.Fab")
		)
		(pad "1" smd circle
			(at -0.40005 0 90)
			(size 0 0)
			(layers "F.Cu" "F.Mask" "F.Paste")
			(net "IRQ_CPU_BMC_NMI_N")
		)
		(pad "2" smd circle
			(at 0.40005 0 90)
			(size 0 0)
			(layers "F.Cu" "F.Mask" "F.Paste")
			(net "IRQ_CPU_BMC_NMI_R_N")
		)
	)
)
